# S9S_MB_2U (Grand Teton) — schematic netlist excerpt (pin names and nets, part order shuffled) for the footprints in the layout excerpt that follows; sources: Cadence DE-HDL packaged netlist, KiCad conversion of 03242023_DA0F0TMBIJ0_F0T_Motherboard_J_brd_V01_OCP.brd

PC2140  Q_CAP  1UF 25V 10% X6S  pkg C0402  page 162 : A = P3V3_AUX ; B = GND
R2449  Q_RES  33.2 1% CHIP  pkg 0402LF  page 241 : A = SMB_VR_3V3AUX_SCL ; B = SMB_VR_3V3AUX_SCL_R1

(kicad_pcb
	(version 20260206)
	(generator "pcbnew")
	(generator_version "10.0")
	(general
		(thickness 1.6)
		(legacy_teardrops no)
	)
	(paper "A4")
	(title_block
		(title "03242023_DA0F0TMBIJ0_F0T_Motherboard_J_brd_V01_OCP.brd")
		(comment 1 "Grand Teton / footprints 612-613 of 6105")
	)
	(layers
		(0 "F.Cu" signal "TOP")
		(4 "In1.Cu" signal "GND")
		(6 "In2.Cu" signal "IN1")
		(8 "In3.Cu" signal "GND1")
		(10 "In4.Cu" signal "IN2")
		(12 "In5.Cu" signal "GND2")
		(14 "In6.Cu" signal "IN3")
		(16 "In7.Cu" signal "GND3")
		(18 "In8.Cu" signal "VCC")
		(20 "In9.Cu" signal "VCC1")
		(22 "In10.Cu" signal "GND4")
		(24 "In11.Cu" signal "IN4")
		(26 "In12.Cu" signal "GND5")
		(28 "In13.Cu" signal "IN5")
		(30 "In14.Cu" signal "GND6")
		(32 "In15.Cu" signal "IN6")
		(34 "In16.Cu" signal "GND7")
		(2 "B.Cu" signal "BOTTOM")
		(9 "F.Adhes" user "F.Adhesive")
		(11 "B.Adhes" user "B.Adhesive")
		(13 "F.Paste" user "Package Geometry/Pastemask Top")
		(15 "B.Paste" user "Package Geometry/Pastemask Bottom")
		(5 "F.SilkS" user "Ref Des/Silkscreen Top")
		(7 "B.SilkS" user "Ref Des/Silkscreen Bottom")
		(1 "F.Mask" user "Board Geometry/Soldermask Top")
		(3 "B.Mask" user "Board Geometry/Soldermask Bottom")
		(17 "Dwgs.User" user "User.Drawings")
		(19 "Cmts.User" user "User.Comments")
		(21 "Eco1.User" user "User.Eco1")
		(23 "Eco2.User" user "User.Eco2")
		(25 "Edge.Cuts" user "Board Geometry/Outline")
		(27 "Margin" user)
		(31 "F.CrtYd" user "Package Geometry/Place Bound Top")
		(29 "B.CrtYd" user "Package Geometry/Place Bound Bottom")
		(35 "F.Fab" user "Ref Des/Assembly Top")
		(33 "B.Fab" user "Ref Des/Assembly Bottom")
	)
	(footprint ""
		(layer "F.Cu")
		(at 87.947246 -57.279286 90)
		(property "Reference" "PC2140"
			(at 0 0 90)
			(layer "F.SilkS")
			(hide yes)
			(effects
				(font
					(size 1.27 1.27)
				)
			)
		)
		(property "Value" ""
			(at 0 0 90)
			(layer "F.Fab")
			(effects
				(font
					(size 1.27 1.27)
				)
			)
		)
		(duplicate_pad_numbers_are_jumpers no)
		(fp_line
			(start 0.7874 -0.4064)
			(end 0.7874 0.4064)
			(stroke
				(width 0.1524)
				(type default)
			)
			(layer "F.SilkS")
		)
		(fp_line
			(start -0.7874 -0.4064)
			(end 0.7874 -0.4064)
			(stroke
				(width 0.1524)
				(type default)
			)
			(layer "F.SilkS")
		)
		(fp_line
			(start 0.7874 0.4064)
			(end -0.7874 0.4064)
			(stroke
				(width 0.1524)
				(type default)
			)
			(layer "F.SilkS")
		)
		(fp_line
			(start -0.7874 0.4064)
			(end -0.7874 -0.4064)
			(stroke
				(width 0.1524)
				(type default)
			)
			(layer "F.SilkS")
		)
		(fp_line
			(start -0.12065 -0.305054)
			(end -0.12065 -0.2794)
			(stroke
				(width 0.1)
				(type default)
			)
			(layer "F.Fab")
		)
		(fp_line
			(start -0.67945 -0.305054)
			(end -0.12065 -0.305054)
			(stroke
				(width 0.1)
				(type default)
			)
			(layer "F.Fab")
		)
		(fp_line
			(start 0.67945 -0.3048)
			(end 0.67945 0.3048)
			(stroke
				(width 0.1)
				(type default)
			)
			(layer "F.Fab")
		)
		(fp_line
			(start 0.12065 -0.3048)
			(end 0.67945 -0.3048)
			(stroke
				(width 0.1)
				(type default)
			)
			(layer "F.Fab")
		)
		(fp_line
			(start 0.12065 -0.2794)
			(end 0.12065 -0.3048)
			(stroke
				(width 0.1)
				(type default)
			)
			(layer "F.Fab")
		)
		(fp_line
			(start -0.12065 -0.2794)
			(end 0.12065 -0.2794)
			(stroke
				(width 0.1)
				(type default)
			)
			(layer "F.Fab")
		)
		(fp_line
			(start 0.120396 0.2794)
			(end -0.12065 0.2794)
			(stroke
				(width 0.1)
				(type default)
			)
			(layer "F.Fab")
		)
		(fp_line
			(start -0.12065 0.2794)
			(end -0.12065 0.3048)
			(stroke
				(width 0.1)
				(type default)
			)
			(layer "F.Fab")
		)
		(fp_line
			(start 0.67945 0.3048)
			(end 0.120396 0.3048)
			(stroke
				(width 0.1)
				(type default)
			)
			(layer "F.Fab")
		)
		(fp_line
			(start 0.120396 0.3048)
			(end 0.120396 0.2794)
			(stroke
				(width 0.1)
				(type default)
			)
			(layer "F.Fab")
		)
		(fp_line
			(start -0.12065 0.3048)
			(end -0.67945 0.3048)
			(stroke
				(width 0.1)
				(type default)
			)
			(layer "F.Fab")
		)
		(fp_line
			(start -0.67945 0.3048)
			(end -0.67945 -0.305054)
			(stroke
				(width 0.1)
				(type default)
			)
			(layer "F.Fab")
		)
		(pad "1" smd circle
			(at -0.40005 0 90)
			(size 0 0)
			(layers "F.Cu" "F.Mask" "F.Paste")
			(net "P3V3_AUX")
		)
		(pad "2" smd circle
			(at 0.40005 0 90)
			(size 0 0)
			(layers "F.Cu" "F.Mask" "F.Paste")
			(net "GND")
		)
	)
	(footprint ""
		(layer "F.Cu")
		(at 36.884102 -122.380502 90)
		(property "Reference" "R2449"
			(at 0 0 90)
			(layer "F.SilkS")
			(hide yes)
			(effects
				(font
					(size 1.27 1.27)
				)
			)
		)
		(property "Value" ""
			(at 0 0 90)
			(layer "F.Fab")
			(effects
				(font
					(size 1.27 1.27)
				)
			)
		)
		(duplicate_pad_numbers_are_jumpers no)
		(fp_line
			(start 0.7874 -0.4064)
			(end 0.7874 0.4064)
			(stroke
				(width 0.1524)
				(type default)
			)
			(layer "F.SilkS")
		)
		(fp_line
			(start -0.7874 -0.4064)
			(end 0.7874 -0.4064)
			(stroke
				(width 0.1524)
				(type default)
			)
			(layer "F.SilkS")
		)
		(fp_line
			(start 0.7874 0.4064)
			(end -0.7874 0.4064)
			(stroke
				(width 0.1524)
				(type default)
			)
			(layer "F.SilkS")
		)
		(fp_line
			(start -0.7874 0.4064)
			(end -0.7874 -0.4064)
			(stroke
				(width 0.1524)
				(type default)
			)
			(layer "F.SilkS")
		)
		(fp_line
			(start -0.12065 -0.305054)
			(end -0.12065 -0.2794)
			(stroke
				(width 0.1)
				(type default)
			)
			(layer "F.Fab")
		)
		(fp_line
			(start -0.67945 -0.305054)
			(end -0.12065 -0.305054)
			(stroke
				(width 0.1)
				(type default)
			)
			(layer "F.Fab")
		)
		(fp_line
			(start 0.67945 -0.3048)
			(end 0.67945 0.3048)
			(stroke
				(width 0.1)
				(type default)
			)
			(layer "F.Fab")
		)
		(fp_line
			(start 0.12065 -0.3048)
			(end 0.67945 -0.3048)
			(stroke
				(width 0.1)
				(type default)
			)
			(layer "F.Fab")
		)
		(fp_line
			(start 0.12065 -0.2794)
			(end 0.12065 -0.3048)
			(stroke
				(width 0.1)
				(type default)
			)
			(layer "F.Fab")
		)
		(fp_line
			(start -0.12065 -0.2794)
			(end 0.12065 -0.2794)
			(stroke
				(width 0.1)
				(type default)
			)
			(layer "F.Fab")
		)
		(fp_line
			(start 0.120396 0.2794)
			(end -0.12065 0.2794)
			(stroke
				(width 0.1)
				(type default)
			)
			(layer "F.Fab")
		)
		(fp_line
			(start -0.12065 0.2794)
			(end -0.12065 0.3048)
			(stroke
				(width 0.1)
				(type default)
			)
			(layer "F.Fab")
		)
		(fp_line
			(start 0.67945 0.3048)
			(end 0.120396 0.3048)
			(stroke
				(width 0.1)
				(type default)
			)
			(layer "F.Fab")
		)
		(fp_line
			(start 0.120396 0.3048)
			(end 0.120396 0.2794)
			(stroke
				(width 0.1)
				(type default)
			)
			(layer "F.Fab")
		)
		(fp_line
			(start -0.12065 0.3048)
			(end -0.67945 0.3048)
			(stroke
				(width 0.1)
				(type default)
			)
			(layer "F.Fab")
		)
		(fp_line
			(start -0.67945 0.3048)
			(end -0.67945 -0.305054)
			(stroke
				(width 0.1)
				(type default)
			)
			(layer "F.Fab")
		)
		(pad "1" smd circle
			(at -0.40005 0 90)
			(size 0 0)
			(layers "F.Cu" "F.Mask" "F.Paste")
			(net "SMB_VR_3V3AUX_SCL")
		)
		(pad "2" smd circle
			(at 0.40005 0 90)
			(size 0 0)
			(layers "F.Cu" "F.Mask" "F.Paste")
			(net "SMB_VR_3V3AUX_SCL_R1")
		)
	)
)
